(kicad_pcb
	(version 20260206)
	(generator "pcbnew")
	(generator_version "10.0")
	(general
		(thickness 1.6)
		(legacy_teardrops no)
	)
	(paper "A4")
	(title_block
		(title "04192023_DAF0TMB3IC0_F0TG_MB_C_brd_V02_OCP.brd")
		(comment 1 "Grand Teton / footprints 2936-2941 of 8354")
	)
	(layers
		(0 "F.Cu" signal "TOP")
		(4 "In1.Cu" signal "GND")
		(6 "In2.Cu" signal "IN1")
		(8 "In3.Cu" signal "GND1")
		(10 "In4.Cu" signal "IN2")
		(12 "In5.Cu" signal "GND2")
		(14 "In6.Cu" signal "IN3")
		(16 "In7.Cu" signal "GND3")
		(18 "In8.Cu" signal "VCC")
		(20 "In9.Cu" signal "VCC1")
		(22 "In10.Cu" signal "GND4")
		(24 "In11.Cu" signal "IN4")
		(26 "In12.Cu" signal "GND5")
		(28 "In13.Cu" signal "IN5")
		(30 "In14.Cu" signal "GND6")
		(32 "In15.Cu" signal "IN6")
		(34 "In16.Cu" signal "GND7")
		(2 "B.Cu" signal "BOTTOM")
		(9 "F.Adhes" user "F.Adhesive")
		(11 "B.Adhes" user "B.Adhesive")
		(13 "F.Paste" user "Package Geometry/Pastemask Top")
		(15 "B.Paste" user "Package Geometry/Pastemask Bottom")
		(5 "F.SilkS" user "Ref Des/Silkscreen Top")
		(7 "B.SilkS" user "Ref Des/Silkscreen Bottom")
		(1 "F.Mask" user "Board Geometry/Soldermask Top")
		(3 "B.Mask" user "Board Geometry/Soldermask Bottom")
		(17 "Dwgs.User" user "User.Drawings")
		(19 "Cmts.User" user "User.Comments")
		(21 "Eco1.User" user "User.Eco1")
		(23 "Eco2.User" user "User.Eco2")
		(25 "Edge.Cuts" user "Board Geometry/Outline")
		(27 "Margin" user)
		(31 "F.CrtYd" user "Package Geometry/Place Bound Top")
		(29 "B.CrtYd" user "Package Geometry/Place Bound Bottom")
		(35 "F.Fab" user "Ref Des/Assembly Top")
		(33 "B.Fab" user "Ref Des/Assembly Bottom")
	)
	(footprint ""
		(layer "F.Cu")
		(at 264.986516 -139.591796 180)
		(property "Reference" "R1530"
			(at 0 0 180)
			(layer "F.SilkS")
			(hide yes)
			(effects
				(font
					(size 1.27 1.27)
				)
			)
		)
		(property "Value" ""
			(at 0 0 180)
			(layer "F.Fab")
			(effects
				(font
					(size 1.27 1.27)
				)
			)
		)
		(duplicate_pad_numbers_are_jumpers no)
		(fp_line
			(start 0.7874 0.4064)
			(end -0.7874 0.4064)
			(stroke
				(width 0.1524)
				(type default)
			)
			(layer "F.SilkS")
		)
		(fp_line
			(start 0.7874 -0.4064)
			(end 0.7874 0.4064)
			(stroke
				(width 0.1524)
				(type default)
			)
			(layer "F.SilkS")
		)
		(fp_line
			(start -0.7874 0.4064)
			(end -0.7874 -0.4064)
			(stroke
				(width 0.1524)
				(type default)
			)
			(layer "F.SilkS")
		)
		(fp_line
			(start -0.7874 -0.4064)
			(end 0.7874 -0.4064)
			(stroke
				(width 0.1524)
				(type default)
			)
			(layer "F.SilkS")
		)
		(fp_line
			(start 0.67945 0.3048)
			(end 0.120396 0.3048)
			(stroke
				(width 0.1)
				(type default)
			)
			(layer "F.Fab")
		)
		(fp_line
			(start 0.67945 -0.3048)
			(end 0.67945 0.3048)
			(stroke
				(width 0.1)
				(type default)
			)
			(layer "F.Fab")
		)
		(fp_line
			(start 0.12065 -0.2794)
			(end 0.12065 -0.3048)
			(stroke
				(width 0.1)
				(type default)
			)
			(layer "F.Fab")
		)
		(fp_line
			(start 0.12065 -0.3048)
			(end 0.67945 -0.3048)
			(stroke
				(width 0.1)
				(type default)
			)
			(layer "F.Fab")
		)
		(fp_line
			(start 0.120396 0.3048)
			(end 0.120396 0.2794)
			(stroke
				(width 0.1)
				(type default)
			)
			(layer "F.Fab")
		)
		(fp_line
			(start 0.120396 0.2794)
			(end -0.12065 0.2794)
			(stroke
				(width 0.1)
				(type default)
			)
			(layer "F.Fab")
		)
		(fp_line
			(start -0.12065 0.3048)
			(end -0.67945 0.3048)
			(stroke
				(width 0.1)
				(type default)
			)
			(layer "F.Fab")
		)
		(fp_line
			(start -0.12065 0.2794)
			(end -0.12065 0.3048)
			(stroke
				(width 0.1)
				(type default)
			)
			(layer "F.Fab")
		)
		(fp_line
			(start -0.12065 -0.2794)
			(end 0.12065 -0.2794)
			(stroke
				(width 0.1)
				(type default)
			)
			(layer "F.Fab")
		)
		(fp_line
			(start -0.12065 -0.305054)
			(end -0.12065 -0.2794)
			(stroke
				(width 0.1)
				(type default)
			)
			(layer "F.Fab")
		)
		(fp_line
			(start -0.67945 0.3048)
			(end -0.67945 -0.305054)
			(stroke
				(width 0.1)
				(type default)
			)
			(layer "F.Fab")
		)
		(fp_line
			(start -0.67945 -0.305054)
			(end -0.12065 -0.305054)
			(stroke
				(width 0.1)
				(type default)
			)
			(layer "F.Fab")
		)
		(pad "1" smd circle
			(at -0.40005 0 180)
			(size 0 0)
			(layers "F.Cu" "F.Mask" "F.Paste")
			(net "PVDD18_S5_P0")
		)
		(pad "2" smd circle
			(at 0.40005 0 180)
			(size 0 0)
			(layers "F.Cu" "F.Mask" "F.Paste")
			(net "SPI_CPU0_D2")
		)
	)
	(footprint ""
		(layer "F.Cu")
		(at 298.159932 -52.63007 90)
		(property "Reference" "J6"
			(at -1.948434 2.597658 0)
			(unlocked yes)
			(layer "F.SilkS")
			(effects
				(font
					(size 0.7874 0.5842)
					(thickness 0.1524)
				)
			)
		)
		(property "Value" ""
			(at 0 0 90)
			(layer "F.Fab")
			(effects
				(font
					(size 1.27 1.27)
				)
			)
		)
		(duplicate_pad_numbers_are_jumpers no)
		(fp_line
			(start 3.759962 -1.335024)
			(end 3.759962 6.415024)
			(stroke
				(width 0.1524)
				(type default)
			)
			(layer "F.SilkS")
		)
		(fp_line
			(start -1.219962 -1.335024)
			(end 3.759962 -1.335024)
			(stroke
				(width 0.1524)
				(type default)
			)
			(layer "F.SilkS")
		)
		(fp_line
			(start 3.759962 6.415024)
			(end -1.219962 6.415024)
			(stroke
				(width 0.1524)
				(type default)
			)
			(layer "F.SilkS")
		)
		(fp_line
			(start -1.219962 6.415024)
			(end -1.219962 -1.335024)
			(stroke
				(width 0.1524)
				(type default)
			)
			(layer "F.SilkS")
		)
		(fp_poly
			(pts
				(xy -1.423162 0) (xy -2.439162 0.508) (xy -2.439162 -0.508)
			)
			(stroke
				(width 0)
				(type default)
			)
			(fill yes)
			(layer "F.SilkS")
		)
		(fp_line
			(start 3.759962 -1.335024)
			(end 3.759962 6.415024)
			(stroke
				(width 0.1)
				(type default)
			)
			(layer "F.Fab")
		)
		(fp_line
			(start -1.219962 -1.335024)
			(end 3.759962 -1.335024)
			(stroke
				(width 0.1)
				(type default)
			)
			(layer "F.Fab")
		)
		(fp_line
			(start 3.759962 6.415024)
			(end -1.219962 6.415024)
			(stroke
				(width 0.1)
				(type default)
			)
			(layer "F.Fab")
		)
		(fp_line
			(start -1.219962 6.415024)
			(end -1.219962 -1.335024)
			(stroke
				(width 0.1)
				(type default)
			)
			(layer "F.Fab")
		)
		(fp_poly
			(pts
				(xy -2.439162 -0.508) (xy -2.439162 0.508) (xy -1.423162 0)
			)
			(stroke
				(width 0)
				(type default)
			)
			(fill yes)
			(layer "F.Fab")
		)
		(pad "1" thru_hole rect
			(at 0 0 90)
			(size 1.6256 1.6256)
			(drill 1.1176)
			(layers "*.Cu" "*.Mask")
			(remove_unused_layers no)
			(net "CPU0_PWR_BTN_N")
			(clearance 0)
			(padstack
				(mode front_inner_back)
				(layer "Inner"
					(shape circle)
					(size 1.6256 1.6256)
					(clearance 0)
				)
				(layer "B.Cu"
					(shape rect)
					(size 1.6256 1.6256)
					(clearance 0)
				)
			)
		)
		(pad "2" thru_hole circle
			(at 2.54 0 90)
			(size 1.6256 1.6256)
			(drill 1.1176)
			(layers "*.Cu" "*.Mask")
			(remove_unused_layers no)
			(net "GND")
			(clearance 0)
		)
		(pad "3" thru_hole circle
			(at 0 2.54 90)
			(size 1.6256 1.6256)
			(drill 1.1176)
			(layers "*.Cu" "*.Mask")
			(remove_unused_layers no)
			(net "RST_CPU0_SYS_N")
			(clearance 0)
		)
		(pad "4" thru_hole circle
			(at 2.54 2.54 90)
			(size 1.6256 1.6256)
			(drill 1.1176)
			(layers "*.Cu" "*.Mask")
			(remove_unused_layers no)
			(net "GND")
			(clearance 0)
		)
		(pad "5" thru_hole circle
			(at 0 5.08 90)
			(size 1.6256 1.6256)
			(drill 1.1176)
			(layers "*.Cu" "*.Mask")
			(remove_unused_layers no)
			(net "Net_10748")
			(clearance 0)
		)
		(pad "6" thru_hole circle
			(at 2.54 5.08 90)
			(size 1.6256 1.6256)
			(drill 1.1176)
			(layers "*.Cu" "*.Mask")
			(remove_unused_layers no)
			(net "GND")
			(clearance 0)
		)
	)
	(footprint ""
		(layer "F.Cu")
		(at 8.75919 -101.854 180)
		(property "Reference" "R3653"
			(at 0 0 180)
			(layer "F.SilkS")
			(hide yes)
			(effects
				(font
					(size 1.27 1.27)
				)
			)
		)
		(property "Value" ""
			(at 0 0 180)
			(layer "F.Fab")
			(effects
				(font
					(size 1.27 1.27)
				)
			)
		)
		(duplicate_pad_numbers_are_jumpers no)
		(fp_line
			(start 0.7874 0.4064)
			(end -0.7874 0.4064)
			(stroke
				(width 0.1524)
				(type default)
			)
			(layer "F.SilkS")
		)
		(fp_line
			(start 0.7874 -0.4064)
			(end 0.7874 0.4064)
			(stroke
				(width 0.1524)
				(type default)
			)
			(layer "F.SilkS")
		)
		(fp_line
			(start -0.7874 0.4064)
			(end -0.7874 -0.4064)
			(stroke
				(width 0.1524)
				(type default)
			)
			(layer "F.SilkS")
		)
		(fp_line
			(start -0.7874 -0.4064)
			(end 0.7874 -0.4064)
			(stroke
				(width 0.1524)
				(type default)
			)
			(layer "F.SilkS")
		)
		(fp_line
			(start 0.67945 0.3048)
			(end 0.120396 0.3048)
			(stroke
				(width 0.1)
				(type default)
			)
			(layer "F.Fab")
		)
		(fp_line
			(start 0.67945 -0.3048)
			(end 0.67945 0.3048)
			(stroke
				(width 0.1)
				(type default)
			)
			(layer "F.Fab")
		)
		(fp_line
			(start 0.12065 -0.2794)
			(end 0.12065 -0.3048)
			(stroke
				(width 0.1)
				(type default)
			)
			(layer "F.Fab")
		)
		(fp_line
			(start 0.12065 -0.3048)
			(end 0.67945 -0.3048)
			(stroke
				(width 0.1)
				(type default)
			)
			(layer "F.Fab")
		)
		(fp_line
			(start 0.120396 0.3048)
			(end 0.120396 0.2794)
			(stroke
				(width 0.1)
				(type default)
			)
			(layer "F.Fab")
		)
		(fp_line
			(start 0.120396 0.2794)
			(end -0.12065 0.2794)
			(stroke
				(width 0.1)
				(type default)
			)
			(layer "F.Fab")
		)
		(fp_line
			(start -0.12065 0.3048)
			(end -0.67945 0.3048)
			(stroke
				(width 0.1)
				(type default)
			)
			(layer "F.Fab")
		)
		(fp_line
			(start -0.12065 0.2794)
			(end -0.12065 0.3048)
			(stroke
				(width 0.1)
				(type default)
			)
			(layer "F.Fab")
		)
		(fp_line
			(start -0.12065 -0.2794)
			(end 0.12065 -0.2794)
			(stroke
				(width 0.1)
				(type default)
			)
			(layer "F.Fab")
		)
		(fp_line
			(start -0.12065 -0.305054)
			(end -0.12065 -0.2794)
			(stroke
				(width 0.1)
				(type default)
			)
			(layer "F.Fab")
		)
		(fp_line
			(start -0.67945 0.3048)
			(end -0.67945 -0.305054)
			(stroke
				(width 0.1)
				(type default)
			)
			(layer "F.Fab")
		)
		(fp_line
			(start -0.67945 -0.305054)
			(end -0.12065 -0.305054)
			(stroke
				(width 0.1)
				(type default)
			)
			(layer "F.Fab")
		)
		(pad "1" smd circle
			(at -0.40005 0 180)
			(size 0 0)
			(layers "F.Cu" "F.Mask" "F.Paste")
			(net "USB_HUB_RREF")
		)
		(pad "2" smd circle
			(at 0.40005 0 180)
			(size 0 0)
			(layers "F.Cu" "F.Mask" "F.Paste")
			(net "GND")
		)
	)
	(footprint ""
		(layer "F.Cu")
		(at 100.941124 -34.28492)
		(property "Reference" "R3193"
			(at 0 0 0)
			(layer "F.SilkS")
			(hide yes)
			(effects
				(font
					(size 1.27 1.27)
				)
			)
		)
		(property "Value" ""
			(at 0 0 0)
			(layer "F.Fab")
			(effects
				(font
					(size 1.27 1.27)
				)
			)
		)
		(duplicate_pad_numbers_are_jumpers no)
		(fp_line
			(start -0.7874 -0.4064)
			(end 0.7874 -0.4064)
			(stroke
				(width 0.1524)
				(type default)
			)
			(layer "F.SilkS")
		)
		(fp_line
			(start -0.7874 0.4064)
			(end -0.7874 -0.4064)
			(stroke
				(width 0.1524)
				(type default)
			)
			(layer "F.SilkS")
		)
		(fp_line
			(start 0.7874 -0.4064)
			(end 0.7874 0.4064)
			(stroke
				(width 0.1524)
				(type default)
			)
			(layer "F.SilkS")
		)
		(fp_line
			(start 0.7874 0.4064)
			(end -0.7874 0.4064)
			(stroke
				(width 0.1524)
				(type default)
			)
			(layer "F.SilkS")
		)
		(fp_line
			(start -0.67945 -0.305054)
			(end -0.12065 -0.305054)
			(stroke
				(width 0.1)
				(type default)
			)
			(layer "F.Fab")
		)
		(fp_line
			(start -0.67945 0.3048)
			(end -0.67945 -0.305054)
			(stroke
				(width 0.1)
				(type default)
			)
			(layer "F.Fab")
		)
		(fp_line
			(start -0.12065 -0.305054)
			(end -0.12065 -0.2794)
			(stroke
				(width 0.1)
				(type default)
			)
			(layer "F.Fab")
		)
		(fp_line
			(start -0.12065 -0.2794)
			(end 0.12065 -0.2794)
			(stroke
				(width 0.1)
				(type default)
			)
			(layer "F.Fab")
		)
		(fp_line
			(start -0.12065 0.2794)
			(end -0.12065 0.3048)
			(stroke
				(width 0.1)
				(type default)
			)
			(layer "F.Fab")
		)
		(fp_line
			(start -0.12065 0.3048)
			(end -0.67945 0.3048)
			(stroke
				(width 0.1)
				(type default)
			)
			(layer "F.Fab")
		)
		(fp_line
			(start 0.120396 0.2794)
			(end -0.12065 0.2794)
			(stroke
				(width 0.1)
				(type default)
			)
			(layer "F.Fab")
		)
		(fp_line
			(start 0.120396 0.3048)
			(end 0.120396 0.2794)
			(stroke
				(width 0.1)
				(type default)
			)
			(layer "F.Fab")
		)
		(fp_line
			(start 0.12065 -0.3048)
			(end 0.67945 -0.3048)
			(stroke
				(width 0.1)
				(type default)
			)
			(layer "F.Fab")
		)
		(fp_line
			(start 0.12065 -0.2794)
			(end 0.12065 -0.3048)
			(stroke
				(width 0.1)
				(type default)
			)
			(layer "F.Fab")
		)
		(fp_line
			(start 0.67945 -0.3048)
			(end 0.67945 0.3048)
			(stroke
				(width 0.1)
				(type default)
			)
			(layer "F.Fab")
		)
		(fp_line
			(start 0.67945 0.3048)
			(end 0.120396 0.3048)
			(stroke
				(width 0.1)
				(type default)
			)
			(layer "F.Fab")
		)
		(pad "1" smd circle
			(at -0.40005 0)
			(size 0 0)
			(layers "F.Cu" "F.Mask" "F.Paste")
			(net "IRQ_LVC3_V3_2_WAKE_BUF_N")
		)
		(pad "2" smd circle
			(at 0.40005 0)
			(size 0 0)
			(layers "F.Cu" "F.Mask" "F.Paste")
			(net "IRQ_OCP_V3_2_WAKE_BUF_N")
		)
	)
	(footprint ""
		(layer "F.Cu")
		(at 235.718096 -144.958562 180)
		(property "Reference" "R1647"
			(at 0 0 180)
			(layer "F.SilkS")
			(hide yes)
			(effects
				(font
					(size 1.27 1.27)
				)
			)
		)
		(property "Value" ""
			(at 0 0 180)
			(layer "F.Fab")
			(effects
				(font
					(size 1.27 1.27)
				)
			)
		)
		(duplicate_pad_numbers_are_jumpers no)
		(fp_line
			(start 0.7874 0.4064)
			(end -0.7874 0.4064)
			(stroke
				(width 0.1524)
				(type default)
			)
			(layer "F.SilkS")
		)
		(fp_line
			(start 0.7874 -0.4064)
			(end 0.7874 0.4064)
			(stroke
				(width 0.1524)
				(type default)
			)
			(layer "F.SilkS")
		)
		(fp_line
			(start -0.7874 0.4064)
			(end -0.7874 -0.4064)
			(stroke
				(width 0.1524)
				(type default)
			)
			(layer "F.SilkS")
		)
		(fp_line
			(start -0.7874 -0.4064)
			(end 0.7874 -0.4064)
			(stroke
				(width 0.1524)
				(type default)
			)
			(layer "F.SilkS")
		)
		(fp_line
			(start 0.67945 0.3048)
			(end 0.120396 0.3048)
			(stroke
				(width 0.1)
				(type default)
			)
			(layer "F.Fab")
		)
		(fp_line
			(start 0.67945 -0.3048)
			(end 0.67945 0.3048)
			(stroke
				(width 0.1)
				(type default)
			)
			(layer "F.Fab")
		)
		(fp_line
			(start 0.12065 -0.2794)
			(end 0.12065 -0.3048)
			(stroke
				(width 0.1)
				(type default)
			)
			(layer "F.Fab")
		)
		(fp_line
			(start 0.12065 -0.3048)
			(end 0.67945 -0.3048)
			(stroke
				(width 0.1)
				(type default)
			)
			(layer "F.Fab")
		)
		(fp_line
			(start 0.120396 0.3048)
			(end 0.120396 0.2794)
			(stroke
				(width 0.1)
				(type default)
			)
			(layer "F.Fab")
		)
		(fp_line
			(start 0.120396 0.2794)
			(end -0.12065 0.2794)
			(stroke
				(width 0.1)
				(type default)
			)
			(layer "F.Fab")
		)
		(fp_line
			(start -0.12065 0.3048)
			(end -0.67945 0.3048)
			(stroke
				(width 0.1)
				(type default)
			)
			(layer "F.Fab")
		)
		(fp_line
			(start -0.12065 0.2794)
			(end -0.12065 0.3048)
			(stroke
				(width 0.1)
				(type default)
			)
			(layer "F.Fab")
		)
		(fp_line
			(start -0.12065 -0.2794)
			(end 0.12065 -0.2794)
			(stroke
				(width 0.1)
				(type default)
			)
			(layer "F.Fab")
		)
		(fp_line
			(start -0.12065 -0.305054)
			(end -0.12065 -0.2794)
			(stroke
				(width 0.1)
				(type default)
			)
			(layer "F.Fab")
		)
		(fp_line
			(start -0.67945 0.3048)
			(end -0.67945 -0.305054)
			(stroke
				(width 0.1)
				(type default)
			)
			(layer "F.Fab")
		)
		(fp_line
			(start -0.67945 -0.305054)
			(end -0.12065 -0.305054)
			(stroke
				(width 0.1)
				(type default)
			)
			(layer "F.Fab")
		)
		(pad "1" smd circle
			(at -0.40005 0 180)
			(size 0 0)
			(layers "F.Cu" "F.Mask" "F.Paste")
			(net "PVDD18_S5_P0")
		)
		(pad "2" smd circle
			(at 0.40005 0 180)
			(size 0 0)
			(layers "F.Cu" "F.Mask" "F.Paste")
			(net "FM_PLD_CPU0_PRSNT_HDT_N")
		)
	)
	(footprint ""
		(layer "F.Cu")
		(at 140.289026 -408.517344 -90)
		(property "Reference" "C6709"
			(at 0 0 270)
			(layer "F.SilkS")
			(hide yes)
			(effects
				(font
					(size 1.27 1.27)
				)
			)
		)
		(property "Value" ""
			(at 0 0 270)
			(layer "F.Fab")
			(effects
				(font
					(size 1.27 1.27)
				)
			)
		)
		(duplicate_pad_numbers_are_jumpers no)
		(fp_line
			(start -0.299974 0.150114)
			(end -0.299974 -0.150114)
			(stroke
				(width 0.1)
				(type default)
			)
			(layer "F.Fab")
		)
		(fp_line
			(start 0.299974 0.150114)
			(end -0.299974 0.150114)
			(stroke
				(width 0.1)
				(type default)
			)
			(layer "F.Fab")
		)
		(fp_line
			(start -0.299974 -0.150114)
			(end 0.299974 -0.150114)
			(stroke
				(width 0.1)
				(type default)
			)
			(layer "F.Fab")
		)
		(fp_line
			(start 0.299974 -0.150114)
			(end 0.299974 0.150114)
			(stroke
				(width 0.1)
				(type default)
			)
			(layer "F.Fab")
		)
		(pad "1" smd rect
			(at -0.2667 0 270)
			(size 0.3048 0.381)
			(layers "F.Cu" "F.Mask" "F.Paste")
			(net "P5E_CPU1_P2_TX_BUF_C_DP<8>")
		)
		(pad "2" smd rect
			(at 0.2667 0 270)
			(size 0.3048 0.381)
			(layers "F.Cu" "F.Mask" "F.Paste")
			(net "P5E_CPU1_P2_TX_BUF_DP<8>")
		)
	)
)
